(kicad_pcb
	(version 20260206)
	(generator "pcbnew")
	(generator_version "10.0")
	(general
		(thickness 1.6)
		(legacy_teardrops no)
	)
	(paper "A4")
	(title_block
		(title "Bryce Canyon_IOM_M2_16342-2_OCP.brd")
		(comment 1 "Bryce Canyon / footprints 998-1004 of 1146")
	)
	(layers
		(0 "F.Cu" signal "TOP")
		(4 "In1.Cu" signal "L2GND")
		(6 "In2.Cu" signal "L3")
		(8 "In3.Cu" signal "L4VCC")
		(10 "In4.Cu" signal "L5VCC")
		(12 "In5.Cu" signal "L6")
		(14 "In6.Cu" signal "L7GND")
		(2 "B.Cu" signal "BOTTOM")
		(9 "F.Adhes" user "F.Adhesive")
		(11 "B.Adhes" user "B.Adhesive")
		(13 "F.Paste" user "Package Geometry/Pastemask Top")
		(15 "B.Paste" user "Package Geometry/Pastemask Bottom")
		(5 "F.SilkS" user "Ref Des/Silkscreen Top")
		(7 "B.SilkS" user "Ref Des/Silkscreen Bottom")
		(1 "F.Mask" user "Board Geometry/Soldermask Top")
		(3 "B.Mask" user "Board Geometry/Soldermask Bottom")
		(17 "Dwgs.User" user "User.Drawings")
		(19 "Cmts.User" user "User.Comments")
		(21 "Eco1.User" user "User.Eco1")
		(23 "Eco2.User" user "User.Eco2")
		(25 "Edge.Cuts" user "Board Geometry/Outline")
		(27 "Margin" user)
		(31 "F.CrtYd" user "Package Geometry/Place Bound Top")
		(29 "B.CrtYd" user "Package Geometry/Place Bound Bottom")
		(35 "F.Fab" user "Ref Des/Assembly Top")
		(33 "B.Fab" user "Ref Des/Assembly Bottom")
	)
	(footprint ""
		(layer "B.Cu")
		(at 10.211562 -139.575032 90)
		(property "Reference" "R233"
			(at 0 0 90)
			(layer "B.SilkS")
			(hide yes)
			(effects
				(font
					(size 1.27 1.27)
				)
				(justify mirror)
			)
		)
		(property "Value" "120R2F-GP"
			(at -0.064008 -3.993896 90)
			(unlocked yes)
			(layer "B.Fab")
			(hide yes)
			(effects
				(font
					(size 1.016 1.016)
					(thickness 0.1524)
				)
				(justify mirror)
			)
		)
		(property "Device Type" "R402H16"
			(at -0.064008 -5.517896 90)
			(unlocked yes)
			(layer "B.Fab")
			(hide yes)
			(effects
				(font
					(size 1.016 1.016)
					(thickness 0.1524)
				)
				(justify mirror)
			)
		)
		(duplicate_pad_numbers_are_jumpers no)
		(fp_line
			(start 0.508 -0.9398)
			(end 0.508 0.9398)
			(stroke
				(width 0.1524)
				(type default)
			)
			(layer "B.SilkS")
		)
		(fp_line
			(start -0.508 -0.9398)
			(end 0.508 -0.9398)
			(stroke
				(width 0.1524)
				(type default)
			)
			(layer "B.SilkS")
		)
		(fp_rect
			(start 0.508 0.9398)
			(end -0.508 -0.9398)
			(stroke
				(width 0)
				(type default)
			)
			(fill no)
			(layer "B.CrtYd")
		)
		(fp_rect
			(start 0.508 0.9398)
			(end -0.508 -0.9398)
			(stroke
				(width 0)
				(type default)
			)
			(fill no)
			(layer "B.Fab")
		)
		(pad "1" smd custom
			(at 0 -0.4445 270)
			(size 0.1397 0.1397)
			(layers "B.Cu" "B.Mask" "B.Paste")
			(net "GND")
			(options
				(clearance outline)
				(anchor circle)
			)
			(primitives
				(gr_poly
					(pts
						(arc
							(start -0.1778 0.2794)
							(mid -0.249642 0.249642)
							(end -0.2794 0.1778)
						)
						(arc
							(start -0.2794 -0.1778)
							(mid -0.249642 -0.249642)
							(end -0.1778 -0.2794)
						)
						(arc
							(start 0.1778 -0.2794)
							(mid 0.249642 -0.249642)
							(end 0.2794 -0.1778)
						)
						(arc
							(start 0.2794 0.1778)
							(mid 0.249642 0.249642)
							(end 0.1778 0.2794)
						)
					)
					(width 0)
					(fill yes)
				)
			)
		)
		(pad "2" smd custom
			(at 0 0.4445 270)
			(size 0.1397 0.1397)
			(layers "B.Cu" "B.Mask" "B.Paste")
			(net "MEMA_0")
			(options
				(clearance outline)
				(anchor circle)
			)
			(primitives
				(gr_poly
					(pts
						(arc
							(start -0.1778 0.2794)
							(mid -0.249642 0.249642)
							(end -0.2794 0.1778)
						)
						(arc
							(start -0.2794 -0.1778)
							(mid -0.249642 -0.249642)
							(end -0.1778 -0.2794)
						)
						(arc
							(start 0.1778 -0.2794)
							(mid 0.249642 -0.249642)
							(end 0.2794 -0.1778)
						)
						(arc
							(start 0.2794 0.1778)
							(mid 0.249642 0.249642)
							(end 0.1778 0.2794)
						)
					)
					(width 0)
					(fill yes)
				)
			)
		)
	)
	(footprint ""
		(layer "B.Cu")
		(at 196.457062 -133.83895 180)
		(property "Reference" "C628"
			(at 0 0 0)
			(layer "B.SilkS")
			(hide yes)
			(effects
				(font
					(size 1.27 1.27)
				)
				(justify mirror)
			)
		)
		(property "Value" "SCD1U16V2KX-3GP"
			(at -1.1811 -2.7051 180)
			(unlocked yes)
			(layer "B.Fab")
			(hide yes)
			(effects
				(font
					(size 1.016 1.016)
					(thickness 0.1524)
				)
				(justify mirror)
			)
		)
		(property "Device Type" "C402H22"
			(at -1.1811 -4.2291 180)
			(unlocked yes)
			(layer "B.Fab")
			(hide yes)
			(effects
				(font
					(size 1.016 1.016)
					(thickness 0.1524)
				)
				(justify mirror)
			)
		)
		(duplicate_pad_numbers_are_jumpers no)
		(fp_rect
			(start 0.4318 0.9525)
			(end -0.4318 -0.9525)
			(stroke
				(width 0)
				(type default)
			)
			(fill no)
			(layer "B.CrtYd")
		)
		(fp_rect
			(start 0.4318 0.9525)
			(end -0.4318 -0.9525)
			(stroke
				(width 0)
				(type default)
			)
			(fill no)
			(layer "B.Fab")
		)
		(pad "1" smd custom
			(at 0 -0.4445)
			(size 0.1524 0.1524)
			(layers "B.Cu" "B.Mask" "B.Paste")
			(net "P3V3_M2")
			(options
				(clearance outline)
				(anchor circle)
			)
			(primitives
				(gr_poly
					(pts
						(arc
							(start 0.3048 0.2032)
							(mid 0.275042 0.275042)
							(end 0.2032 0.3048)
						)
						(arc
							(start -0.2032 0.3048)
							(mid -0.275042 0.275042)
							(end -0.3048 0.2032)
						)
						(arc
							(start -0.3048 -0.2032)
							(mid -0.275042 -0.275042)
							(end -0.2032 -0.3048)
						)
						(arc
							(start 0.2032 -0.3048)
							(mid 0.275042 -0.275042)
							(end 0.3048 -0.2032)
						)
					)
					(width 0)
					(fill yes)
				)
			)
		)
		(pad "2" smd custom
			(at 0 0.4445)
			(size 0.1524 0.1524)
			(layers "B.Cu" "B.Mask" "B.Paste")
			(net "GND")
			(options
				(clearance outline)
				(anchor circle)
			)
			(primitives
				(gr_poly
					(pts
						(arc
							(start 0.3048 0.2032)
							(mid 0.275042 0.275042)
							(end 0.2032 0.3048)
						)
						(arc
							(start -0.2032 0.3048)
							(mid -0.275042 0.275042)
							(end -0.3048 0.2032)
						)
						(arc
							(start -0.3048 -0.2032)
							(mid -0.275042 -0.275042)
							(end -0.2032 -0.3048)
						)
						(arc
							(start 0.2032 -0.3048)
							(mid 0.275042 -0.275042)
							(end 0.3048 -0.2032)
						)
					)
					(width 0)
					(fill yes)
				)
			)
		)
	)
	(footprint ""
		(layer "B.Cu")
		(at 67.306952 -169.282618 -90)
		(property "Reference" "R79"
			(at 0 0 90)
			(layer "B.SilkS")
			(hide yes)
			(effects
				(font
					(size 1.27 1.27)
				)
				(justify mirror)
			)
		)
		(property "Value" "470KR2F-GP"
			(at -0.064008 -3.993896 270)
			(unlocked yes)
			(layer "B.Fab")
			(hide yes)
			(effects
				(font
					(size 1.016 1.016)
					(thickness 0.1524)
				)
				(justify mirror)
			)
		)
		(property "Device Type" "R402H16"
			(at -0.064008 -5.517896 270)
			(unlocked yes)
			(layer "B.Fab")
			(hide yes)
			(effects
				(font
					(size 1.016 1.016)
					(thickness 0.1524)
				)
				(justify mirror)
			)
		)
		(duplicate_pad_numbers_are_jumpers no)
		(fp_line
			(start -0.508 -0.9398)
			(end 0.508 -0.9398)
			(stroke
				(width 0.1524)
				(type default)
			)
			(layer "B.SilkS")
		)
		(fp_line
			(start 0.508 -0.9398)
			(end 0.508 0.9398)
			(stroke
				(width 0.1524)
				(type default)
			)
			(layer "B.SilkS")
		)
		(fp_rect
			(start 0.508 0.9398)
			(end -0.508 -0.9398)
			(stroke
				(width 0)
				(type default)
			)
			(fill no)
			(layer "B.CrtYd")
		)
		(fp_rect
			(start 0.508 0.9398)
			(end -0.508 -0.9398)
			(stroke
				(width 0)
				(type default)
			)
			(fill no)
			(layer "B.Fab")
		)
		(pad "1" smd custom
			(at 0 -0.4445 90)
			(size 0.1397 0.1397)
			(layers "B.Cu" "B.Mask" "B.Paste")
			(net "BMC_SELF_HW_RST_D")
			(options
				(clearance outline)
				(anchor circle)
			)
			(primitives
				(gr_poly
					(pts
						(arc
							(start -0.1778 0.2794)
							(mid -0.249642 0.249642)
							(end -0.2794 0.1778)
						)
						(arc
							(start -0.2794 -0.1778)
							(mid -0.249642 -0.249642)
							(end -0.1778 -0.2794)
						)
						(arc
							(start 0.1778 -0.2794)
							(mid 0.249642 -0.249642)
							(end 0.2794 -0.1778)
						)
						(arc
							(start 0.2794 0.1778)
							(mid 0.249642 0.249642)
							(end 0.1778 0.2794)
						)
					)
					(width 0)
					(fill yes)
				)
			)
		)
		(pad "2" smd custom
			(at 0 0.4445 90)
			(size 0.1397 0.1397)
			(layers "B.Cu" "B.Mask" "B.Paste")
			(net "GND")
			(options
				(clearance outline)
				(anchor circle)
			)
			(primitives
				(gr_poly
					(pts
						(arc
							(start -0.1778 0.2794)
							(mid -0.249642 0.249642)
							(end -0.2794 0.1778)
						)
						(arc
							(start -0.2794 -0.1778)
							(mid -0.249642 -0.249642)
							(end -0.1778 -0.2794)
						)
						(arc
							(start 0.1778 -0.2794)
							(mid 0.249642 -0.249642)
							(end 0.2794 -0.1778)
						)
						(arc
							(start 0.2794 0.1778)
							(mid 0.249642 0.249642)
							(end 0.1778 0.2794)
						)
					)
					(width 0)
					(fill yes)
				)
			)
		)
	)
	(footprint ""
		(layer "B.Cu")
		(at 207.159352 -105.724198 180)
		(property "Reference" "U82"
			(at 0 0 0)
			(layer "B.SilkS")
			(hide yes)
			(effects
				(font
					(size 1.27 1.27)
				)
				(justify mirror)
			)
		)
		(property "Value" "PCA9306DCTT-GP"
			(at 0 -11.6332 180)
			(unlocked yes)
			(layer "B.Fab")
			(hide yes)
			(effects
				(font
					(size 1.016 1.016)
					(thickness 0.1524)
				)
				(justify mirror)
			)
		)
		(property "Device Type" "SSOIC8H52"
			(at 0 -13.1572 180)
			(unlocked yes)
			(layer "B.Fab")
			(hide yes)
			(effects
				(font
					(size 1.016 1.016)
					(thickness 0.1524)
				)
				(justify mirror)
			)
		)
		(duplicate_pad_numbers_are_jumpers no)
		(fp_line
			(start 1.7018 -0.5842)
			(end 1.7018 2.286)
			(stroke
				(width 0.1524)
				(type default)
			)
			(layer "B.SilkS")
		)
		(fp_line
			(start 1.7018 -0.5842)
			(end -1.0668 -0.5842)
			(stroke
				(width 0.1524)
				(type default)
			)
			(layer "B.SilkS")
		)
		(fp_line
			(start 1.524 0.5842)
			(end 1.524 2.286)
			(stroke
				(width 0.508)
				(type default)
			)
			(layer "B.SilkS")
		)
		(fp_line
			(start 1.397 0)
			(end 1.7018 0.3048)
			(stroke
				(width 0.1524)
				(type default)
			)
			(layer "B.SilkS")
		)
		(fp_line
			(start 1.397 0)
			(end 1.7018 -0.3048)
			(stroke
				(width 0.1524)
				(type default)
			)
			(layer "B.SilkS")
		)
		(fp_line
			(start -1.0668 0.5842)
			(end 1.524 0.5842)
			(stroke
				(width 0.1524)
				(type default)
			)
			(layer "B.SilkS")
		)
		(fp_line
			(start -1.0668 -0.5842)
			(end -1.0668 0.5842)
			(stroke
				(width 0.1524)
				(type default)
			)
			(layer "B.SilkS")
		)
		(fp_poly
			(pts
				(xy 1.1684 -0.5842) (xy -1.0668 -0.5842) (xy -1.0668 0.5842) (xy 1.1684 0.5842)
			)
			(stroke
				(width 0)
				(type default)
			)
			(fill yes)
			(layer "B.SilkS")
		)
		(fp_poly
			(pts
				(xy 1.778 2.54) (xy -1.778 2.54) (xy -1.778 -2.54) (xy 1.778 -2.54)
			)
			(stroke
				(width 0)
				(type default)
			)
			(fill no)
			(layer "B.CrtYd")
		)
		(fp_poly
			(pts
				(xy 1.778 -2.54) (xy -1.778 -2.54) (xy -1.778 2.54) (xy 1.778 2.54)
			)
			(stroke
				(width 0)
				(type default)
			)
			(fill no)
			(layer "B.Fab")
		)
		(pad "1" smd rect
			(at 0.97536 1.6256)
			(size 0.3556 1.524)
			(layers "B.Cu" "B.Mask" "B.Paste")
			(net "GND")
		)
		(pad "2" smd rect
			(at 0.32512 1.6256)
			(size 0.3556 1.524)
			(layers "B.Cu" "B.Mask" "B.Paste")
			(net "P1V8_STBY")
		)
		(pad "3" smd rect
			(at -0.32512 1.6256)
			(size 0.3556 1.524)
			(layers "B.Cu" "B.Mask" "B.Paste")
			(net "I2C_M2_1_1V8_SCL")
		)
		(pad "4" smd rect
			(at -0.97536 1.6256)
			(size 0.3556 1.524)
			(layers "B.Cu" "B.Mask" "B.Paste")
			(net "I2C_M2_1_1V8_SDA")
		)
		(pad "5" smd rect
			(at -0.97536 -1.6256)
			(size 0.3556 1.524)
			(layers "B.Cu" "B.Mask" "B.Paste")
			(net "I2C_M2_1_SDA")
		)
		(pad "6" smd rect
			(at -0.32512 -1.6256)
			(size 0.3556 1.524)
			(layers "B.Cu" "B.Mask" "B.Paste")
			(net "I2C_M2_1_SCL")
		)
		(pad "7" smd rect
			(at 0.32512 -1.6256)
			(size 0.3556 1.524)
			(layers "B.Cu" "B.Mask" "B.Paste")
			(net "U82_VREF2")
		)
		(pad "8" smd rect
			(at 0.97536 -1.6256)
			(size 0.3556 1.524)
			(layers "B.Cu" "B.Mask" "B.Paste")
			(net "U82_VREF2")
		)
	)
	(footprint ""
		(layer "B.Cu")
		(at 50.1396 -139.446)
		(property "Reference" "TP72"
			(at 0 0 0)
			(layer "B.SilkS")
			(hide yes)
			(effects
				(font
					(size 1.27 1.27)
				)
				(justify mirror)
			)
		)
		(property "Value" "TPAD28-2-GP"
			(at 0.0127 -1.6637 0)
			(unlocked yes)
			(layer "B.Fab")
			(hide yes)
			(effects
				(font
					(size 1.016 1.016)
					(thickness 0.1524)
				)
				(justify mirror)
			)
		)
		(property "Device Type" "TPAD28"
			(at 0.0127 -3.1877 0)
			(unlocked yes)
			(layer "B.Fab")
			(hide yes)
			(effects
				(font
					(size 1.016 1.016)
					(thickness 0.1524)
				)
				(justify mirror)
			)
		)
		(duplicate_pad_numbers_are_jumpers no)
		(fp_poly
			(pts
				(arc
					(start 0.3556 0)
					(mid -0.3556 0)
					(end 0.3556 0)
				)
			)
			(stroke
				(width 0)
				(type default)
			)
			(fill no)
			(layer "B.CrtYd")
		)
		(fp_poly
			(pts
				(arc
					(start 0.6096 0)
					(mid -0.6096 0)
					(end 0.6096 0)
				)
			)
			(stroke
				(width 0)
				(type default)
			)
			(fill no)
			(layer "B.Fab")
		)
		(pad "1" smd circle
			(at 0 0 180)
			(size 0.7112 0.7112)
			(layers "B.Cu" "B.Mask" "B.Paste")
			(net "TP_BMC_GPIOI1")
		)
	)
	(footprint ""
		(layer "B.Cu")
		(at 57.0738 -151.6888 -90)
		(property "Reference" "R383"
			(at 0 0 90)
			(layer "B.SilkS")
			(hide yes)
			(effects
				(font
					(size 1.27 1.27)
				)
				(justify mirror)
			)
		)
		(property "Value" "4K7R2F-GP"
			(at -0.064008 -3.993896 270)
			(unlocked yes)
			(layer "B.Fab")
			(hide yes)
			(effects
				(font
					(size 1.016 1.016)
					(thickness 0.1524)
				)
				(justify mirror)
			)
		)
		(property "Device Type" "R402H16"
			(at -0.064008 -5.517896 270)
			(unlocked yes)
			(layer "B.Fab")
			(hide yes)
			(effects
				(font
					(size 1.016 1.016)
					(thickness 0.1524)
				)
				(justify mirror)
			)
		)
		(duplicate_pad_numbers_are_jumpers no)
		(fp_line
			(start -0.508 -0.9398)
			(end 0.508 -0.9398)
			(stroke
				(width 0.1524)
				(type default)
			)
			(layer "B.SilkS")
		)
		(fp_line
			(start 0.508 -0.9398)
			(end 0.508 0.9398)
			(stroke
				(width 0.1524)
				(type default)
			)
			(layer "B.SilkS")
		)
		(fp_rect
			(start 0.508 0.9398)
			(end -0.508 -0.9398)
			(stroke
				(width 0)
				(type default)
			)
			(fill no)
			(layer "B.CrtYd")
		)
		(fp_rect
			(start 0.508 0.9398)
			(end -0.508 -0.9398)
			(stroke
				(width 0)
				(type default)
			)
			(fill no)
			(layer "B.Fab")
		)
		(pad "1" smd custom
			(at 0 -0.4445 90)
			(size 0.1397 0.1397)
			(layers "B.Cu" "B.Mask" "B.Paste")
			(net "P3V3_STBY")
			(options
				(clearance outline)
				(anchor circle)
			)
			(primitives
				(gr_poly
					(pts
						(arc
							(start -0.1778 0.2794)
							(mid -0.249642 0.249642)
							(end -0.2794 0.1778)
						)
						(arc
							(start -0.2794 -0.1778)
							(mid -0.249642 -0.249642)
							(end -0.1778 -0.2794)
						)
						(arc
							(start 0.1778 -0.2794)
							(mid 0.249642 -0.249642)
							(end 0.2794 -0.1778)
						)
						(arc
							(start 0.2794 0.1778)
							(mid 0.249642 0.249642)
							(end 0.1778 0.2794)
						)
					)
					(width 0)
					(fill yes)
				)
			)
		)
		(pad "2" smd custom
			(at 0 0.4445 90)
			(size 0.1397 0.1397)
			(layers "B.Cu" "B.Mask" "B.Paste")
			(net "MAC1_TXD2")
			(options
				(clearance outline)
				(anchor circle)
			)
			(primitives
				(gr_poly
					(pts
						(arc
							(start -0.1778 0.2794)
							(mid -0.249642 0.249642)
							(end -0.2794 0.1778)
						)
						(arc
							(start -0.2794 -0.1778)
							(mid -0.249642 -0.249642)
							(end -0.1778 -0.2794)
						)
						(arc
							(start 0.1778 -0.2794)
							(mid 0.249642 -0.249642)
							(end 0.2794 -0.1778)
						)
						(arc
							(start 0.2794 0.1778)
							(mid 0.249642 0.249642)
							(end 0.1778 0.2794)
						)
					)
					(width 0)
					(fill yes)
				)
			)
		)
	)
	(footprint ""
		(layer "B.Cu")
		(at 49.787302 -135.75665 180)
		(property "Reference" "R291"
			(at 0 0 0)
			(layer "B.SilkS")
			(hide yes)
			(effects
				(font
					(size 1.27 1.27)
				)
				(justify mirror)
			)
		)
		(property "Value" "0R2J-2-GP"
			(at -0.064008 -3.993896 180)
			(unlocked yes)
			(layer "B.Fab")
			(hide yes)
			(effects
				(font
					(size 1.016 1.016)
					(thickness 0.1524)
				)
				(justify mirror)
			)
		)
		(property "Device Type" "R402H16"
			(at -0.064008 -5.517896 180)
			(unlocked yes)
			(layer "B.Fab")
			(hide yes)
			(effects
				(font
					(size 1.016 1.016)
					(thickness 0.1524)
				)
				(justify mirror)
			)
		)
		(duplicate_pad_numbers_are_jumpers no)
		(fp_line
			(start 0.508 -0.9398)
			(end 0.508 0.9398)
			(stroke
				(width 0.1524)
				(type default)
			)
			(layer "B.SilkS")
		)
		(fp_line
			(start -0.508 -0.9398)
			(end 0.508 -0.9398)
			(stroke
				(width 0.1524)
				(type default)
			)
			(layer "B.SilkS")
		)
		(fp_rect
			(start 0.508 0.9398)
			(end -0.508 -0.9398)
			(stroke
				(width 0)
				(type default)
			)
			(fill no)
			(layer "B.CrtYd")
		)
		(fp_rect
			(start 0.508 0.9398)
			(end -0.508 -0.9398)
			(stroke
				(width 0)
				(type default)
			)
			(fill no)
			(layer "B.Fab")
		)
		(pad "1" smd custom
			(at 0 -0.4445)
			(size 0.1397 0.1397)
			(layers "B.Cu" "B.Mask" "B.Paste")
			(net "DPB_MISC_ALERT_OUT")
			(options
				(clearance outline)
				(anchor circle)
			)
			(primitives
				(gr_poly
					(pts
						(arc
							(start -0.1778 0.2794)
							(mid -0.249642 0.249642)
							(end -0.2794 0.1778)
						)
						(arc
							(start -0.2794 -0.1778)
							(mid -0.249642 -0.249642)
							(end -0.1778 -0.2794)
						)
						(arc
							(start 0.1778 -0.2794)
							(mid 0.249642 -0.249642)
							(end 0.2794 -0.1778)
						)
						(arc
							(start 0.2794 0.1778)
							(mid 0.249642 0.249642)
							(end 0.1778 0.2794)
						)
					)
					(width 0)
					(fill yes)
				)
			)
		)
		(pad "2" smd custom
			(at 0 0.4445)
			(size 0.1397 0.1397)
			(layers "B.Cu" "B.Mask" "B.Paste")
			(net "DPB_MISC_ALERT_O_R")
			(options
				(clearance outline)
				(anchor circle)
			)
			(primitives
				(gr_poly
					(pts
						(arc
							(start -0.1778 0.2794)
							(mid -0.249642 0.249642)
							(end -0.2794 0.1778)
						)
						(arc
							(start -0.2794 -0.1778)
							(mid -0.249642 -0.249642)
							(end -0.1778 -0.2794)
						)
						(arc
							(start 0.1778 -0.2794)
							(mid 0.249642 -0.249642)
							(end 0.2794 -0.1778)
						)
						(arc
							(start 0.2794 0.1778)
							(mid 0.249642 0.249642)
							(end 0.1778 0.2794)
						)
					)
					(width 0)
					(fill yes)
				)
			)
		)
	)
)
